(kicad_pcb
	(version 20260206)
	(generator "pcbnew")
	(generator_version "10.0")
	(general
		(thickness 1.6)
		(legacy_teardrops no)
	)
	(paper "A4")
	(title_block
		(title "01162023_DA0F0TEBIF0_F0T_Expander_BD_F_brd_V02_OCP.brd")
		(comment 1 "Grand Teton / footprints 6507-6511 of 9728")
	)
	(layers
		(0 "F.Cu" signal "TOP")
		(4 "In1.Cu" signal "GND")
		(6 "In2.Cu" signal "VCC")
		(8 "In3.Cu" signal "VCC1")
		(10 "In4.Cu" signal "GND1")
		(12 "In5.Cu" signal "IN1")
		(14 "In6.Cu" signal "GND2")
		(16 "In7.Cu" signal "IN2")
		(18 "In8.Cu" signal "GND3")
		(20 "In9.Cu" signal "IN3")
		(22 "In10.Cu" signal "GND4")
		(24 "In11.Cu" signal "IN4")
		(26 "In12.Cu" signal "GND5")
		(28 "In13.Cu" signal "IN5")
		(30 "In14.Cu" signal "GND6")
		(32 "In15.Cu" signal "IN6")
		(34 "In16.Cu" signal "GND7")
		(2 "B.Cu" signal "BOTTOM")
		(9 "F.Adhes" user "F.Adhesive")
		(11 "B.Adhes" user "B.Adhesive")
		(13 "F.Paste" user "Package Geometry/Pastemask Top")
		(15 "B.Paste" user "Package Geometry/Pastemask Bottom")
		(5 "F.SilkS" user "Ref Des/Silkscreen Top")
		(7 "B.SilkS" user "Ref Des/Silkscreen Bottom")
		(1 "F.Mask" user "Board Geometry/Soldermask Top")
		(3 "B.Mask" user "Board Geometry/Soldermask Bottom")
		(17 "Dwgs.User" user "User.Drawings")
		(19 "Cmts.User" user "User.Comments")
		(21 "Eco1.User" user "User.Eco1")
		(23 "Eco2.User" user "User.Eco2")
		(25 "Edge.Cuts" user "Board Geometry/Outline")
		(27 "Margin" user)
		(31 "F.CrtYd" user "Package Geometry/Place Bound Top")
		(29 "B.CrtYd" user "Package Geometry/Place Bound Bottom")
		(35 "F.Fab" user "Ref Des/Assembly Top")
		(33 "B.Fab" user "Ref Des/Assembly Bottom")
	)
	(footprint ""
		(layer "F.Cu")
		(at 433.83581 -289.230816 -90)
		(property "Reference" "R6401"
			(at 0 0 270)
			(layer "F.SilkS")
			(hide yes)
			(effects
				(font
					(size 1.27 1.27)
				)
			)
		)
		(property "Value" ""
			(at 0 0 270)
			(layer "F.Fab")
			(effects
				(font
					(size 1.27 1.27)
				)
			)
		)
		(duplicate_pad_numbers_are_jumpers no)
		(fp_line
			(start -0.7874 0.4064)
			(end -0.7874 -0.4064)
			(stroke
				(width 0.1524)
				(type default)
			)
			(layer "F.SilkS")
		)
		(fp_line
			(start 0.7874 0.4064)
			(end -0.7874 0.4064)
			(stroke
				(width 0.1524)
				(type default)
			)
			(layer "F.SilkS")
		)
		(fp_line
			(start -0.7874 -0.4064)
			(end 0.7874 -0.4064)
			(stroke
				(width 0.1524)
				(type default)
			)
			(layer "F.SilkS")
		)
		(fp_line
			(start 0.7874 -0.4064)
			(end 0.7874 0.4064)
			(stroke
				(width 0.1524)
				(type default)
			)
			(layer "F.SilkS")
		)
		(fp_line
			(start -0.67945 0.3048)
			(end -0.67945 -0.305054)
			(stroke
				(width 0.1)
				(type default)
			)
			(layer "F.Fab")
		)
		(fp_line
			(start -0.12065 0.3048)
			(end -0.67945 0.3048)
			(stroke
				(width 0.1)
				(type default)
			)
			(layer "F.Fab")
		)
		(fp_line
			(start 0.120396 0.3048)
			(end 0.120396 0.2794)
			(stroke
				(width 0.1)
				(type default)
			)
			(layer "F.Fab")
		)
		(fp_line
			(start 0.67945 0.3048)
			(end 0.120396 0.3048)
			(stroke
				(width 0.1)
				(type default)
			)
			(layer "F.Fab")
		)
		(fp_line
			(start -0.12065 0.2794)
			(end -0.12065 0.3048)
			(stroke
				(width 0.1)
				(type default)
			)
			(layer "F.Fab")
		)
		(fp_line
			(start 0.120396 0.2794)
			(end -0.12065 0.2794)
			(stroke
				(width 0.1)
				(type default)
			)
			(layer "F.Fab")
		)
		(fp_line
			(start -0.12065 -0.2794)
			(end 0.12065 -0.2794)
			(stroke
				(width 0.1)
				(type default)
			)
			(layer "F.Fab")
		)
		(fp_line
			(start 0.12065 -0.2794)
			(end 0.12065 -0.3048)
			(stroke
				(width 0.1)
				(type default)
			)
			(layer "F.Fab")
		)
		(fp_line
			(start 0.12065 -0.3048)
			(end 0.67945 -0.3048)
			(stroke
				(width 0.1)
				(type default)
			)
			(layer "F.Fab")
		)
		(fp_line
			(start 0.67945 -0.3048)
			(end 0.67945 0.3048)
			(stroke
				(width 0.1)
				(type default)
			)
			(layer "F.Fab")
		)
		(fp_line
			(start -0.67945 -0.305054)
			(end -0.12065 -0.305054)
			(stroke
				(width 0.1)
				(type default)
			)
			(layer "F.Fab")
		)
		(fp_line
			(start -0.12065 -0.305054)
			(end -0.12065 -0.2794)
			(stroke
				(width 0.1)
				(type default)
			)
			(layer "F.Fab")
		)
		(pad "1" smd circle
			(at -0.40005 0 270)
			(size 0 0)
			(layers "F.Cu" "F.Mask" "F.Paste")
			(net "RST_PEX3_S0_PERST_N")
		)
		(pad "2" smd circle
			(at 0.40005 0 270)
			(size 0 0)
			(layers "F.Cu" "F.Mask" "F.Paste")
			(net "RST_PEX3_S0_PERST_R_N")
		)
	)
	(footprint ""
		(layer "F.Cu")
		(at 101.22408 -246.83212)
		(property "Reference" "R821"
			(at 0 0 0)
			(layer "F.SilkS")
			(hide yes)
			(effects
				(font
					(size 1.27 1.27)
				)
			)
		)
		(property "Value" ""
			(at 0 0 0)
			(layer "F.Fab")
			(effects
				(font
					(size 1.27 1.27)
				)
			)
		)
		(duplicate_pad_numbers_are_jumpers no)
		(fp_line
			(start -0.7874 -0.4064)
			(end 0.7874 -0.4064)
			(stroke
				(width 0.1524)
				(type default)
			)
			(layer "F.SilkS")
		)
		(fp_line
			(start -0.7874 0.4064)
			(end -0.7874 -0.4064)
			(stroke
				(width 0.1524)
				(type default)
			)
			(layer "F.SilkS")
		)
		(fp_line
			(start 0.7874 -0.4064)
			(end 0.7874 0.4064)
			(stroke
				(width 0.1524)
				(type default)
			)
			(layer "F.SilkS")
		)
		(fp_line
			(start 0.7874 0.4064)
			(end -0.7874 0.4064)
			(stroke
				(width 0.1524)
				(type default)
			)
			(layer "F.SilkS")
		)
		(fp_line
			(start -0.67945 -0.305054)
			(end -0.12065 -0.305054)
			(stroke
				(width 0.1)
				(type default)
			)
			(layer "F.Fab")
		)
		(fp_line
			(start -0.67945 0.3048)
			(end -0.67945 -0.305054)
			(stroke
				(width 0.1)
				(type default)
			)
			(layer "F.Fab")
		)
		(fp_line
			(start -0.12065 -0.305054)
			(end -0.12065 -0.2794)
			(stroke
				(width 0.1)
				(type default)
			)
			(layer "F.Fab")
		)
		(fp_line
			(start -0.12065 -0.2794)
			(end 0.12065 -0.2794)
			(stroke
				(width 0.1)
				(type default)
			)
			(layer "F.Fab")
		)
		(fp_line
			(start -0.12065 0.2794)
			(end -0.12065 0.3048)
			(stroke
				(width 0.1)
				(type default)
			)
			(layer "F.Fab")
		)
		(fp_line
			(start -0.12065 0.3048)
			(end -0.67945 0.3048)
			(stroke
				(width 0.1)
				(type default)
			)
			(layer "F.Fab")
		)
		(fp_line
			(start 0.120396 0.2794)
			(end -0.12065 0.2794)
			(stroke
				(width 0.1)
				(type default)
			)
			(layer "F.Fab")
		)
		(fp_line
			(start 0.120396 0.3048)
			(end 0.120396 0.2794)
			(stroke
				(width 0.1)
				(type default)
			)
			(layer "F.Fab")
		)
		(fp_line
			(start 0.12065 -0.3048)
			(end 0.67945 -0.3048)
			(stroke
				(width 0.1)
				(type default)
			)
			(layer "F.Fab")
		)
		(fp_line
			(start 0.12065 -0.2794)
			(end 0.12065 -0.3048)
			(stroke
				(width 0.1)
				(type default)
			)
			(layer "F.Fab")
		)
		(fp_line
			(start 0.67945 -0.3048)
			(end 0.67945 0.3048)
			(stroke
				(width 0.1)
				(type default)
			)
			(layer "F.Fab")
		)
		(fp_line
			(start 0.67945 0.3048)
			(end 0.120396 0.3048)
			(stroke
				(width 0.1)
				(type default)
			)
			(layer "F.Fab")
		)
		(pad "1" smd circle
			(at -0.40005 0)
			(size 0 0)
			(layers "F.Cu" "F.Mask" "F.Paste")
			(net "P1V8_PEX_R")
		)
		(pad "2" smd circle
			(at 0.40005 0)
			(size 0 0)
			(layers "F.Cu" "F.Mask" "F.Paste")
			(net "P12V_PEX_P1V8_VIN_P")
		)
	)
	(footprint ""
		(layer "F.Cu")
		(at 239.47247 -55.80507 90)
		(property "Reference" "PR273"
			(at 0 0 90)
			(layer "F.SilkS")
			(hide yes)
			(effects
				(font
					(size 1.27 1.27)
				)
			)
		)
		(property "Value" ""
			(at 0 0 90)
			(layer "F.Fab")
			(effects
				(font
					(size 1.27 1.27)
				)
			)
		)
		(duplicate_pad_numbers_are_jumpers no)
		(fp_line
			(start 0.7874 -0.4064)
			(end 0.7874 0.4064)
			(stroke
				(width 0.1524)
				(type default)
			)
			(layer "F.SilkS")
		)
		(fp_line
			(start -0.7874 -0.4064)
			(end 0.7874 -0.4064)
			(stroke
				(width 0.1524)
				(type default)
			)
			(layer "F.SilkS")
		)
		(fp_line
			(start 0.7874 0.4064)
			(end -0.7874 0.4064)
			(stroke
				(width 0.1524)
				(type default)
			)
			(layer "F.SilkS")
		)
		(fp_line
			(start -0.7874 0.4064)
			(end -0.7874 -0.4064)
			(stroke
				(width 0.1524)
				(type default)
			)
			(layer "F.SilkS")
		)
		(fp_line
			(start -0.12065 -0.305054)
			(end -0.12065 -0.2794)
			(stroke
				(width 0.1)
				(type default)
			)
			(layer "F.Fab")
		)
		(fp_line
			(start -0.67945 -0.305054)
			(end -0.12065 -0.305054)
			(stroke
				(width 0.1)
				(type default)
			)
			(layer "F.Fab")
		)
		(fp_line
			(start 0.67945 -0.3048)
			(end 0.67945 0.3048)
			(stroke
				(width 0.1)
				(type default)
			)
			(layer "F.Fab")
		)
		(fp_line
			(start 0.12065 -0.3048)
			(end 0.67945 -0.3048)
			(stroke
				(width 0.1)
				(type default)
			)
			(layer "F.Fab")
		)
		(fp_line
			(start 0.12065 -0.2794)
			(end 0.12065 -0.3048)
			(stroke
				(width 0.1)
				(type default)
			)
			(layer "F.Fab")
		)
		(fp_line
			(start -0.12065 -0.2794)
			(end 0.12065 -0.2794)
			(stroke
				(width 0.1)
				(type default)
			)
			(layer "F.Fab")
		)
		(fp_line
			(start 0.120396 0.2794)
			(end -0.12065 0.2794)
			(stroke
				(width 0.1)
				(type default)
			)
			(layer "F.Fab")
		)
		(fp_line
			(start -0.12065 0.2794)
			(end -0.12065 0.3048)
			(stroke
				(width 0.1)
				(type default)
			)
			(layer "F.Fab")
		)
		(fp_line
			(start 0.67945 0.3048)
			(end 0.120396 0.3048)
			(stroke
				(width 0.1)
				(type default)
			)
			(layer "F.Fab")
		)
		(fp_line
			(start 0.120396 0.3048)
			(end 0.120396 0.2794)
			(stroke
				(width 0.1)
				(type default)
			)
			(layer "F.Fab")
		)
		(fp_line
			(start -0.12065 0.3048)
			(end -0.67945 0.3048)
			(stroke
				(width 0.1)
				(type default)
			)
			(layer "F.Fab")
		)
		(fp_line
			(start -0.67945 0.3048)
			(end -0.67945 -0.305054)
			(stroke
				(width 0.1)
				(type default)
			)
			(layer "F.Fab")
		)
		(pad "1" smd circle
			(at -0.40005 0 90)
			(size 0 0)
			(layers "F.Cu" "F.Mask" "F.Paste")
			(net "P3V3_SSD8_OCP")
		)
		(pad "2" smd circle
			(at 0.40005 0 90)
			(size 0 0)
			(layers "F.Cu" "F.Mask" "F.Paste")
			(net "GND")
		)
	)
	(footprint ""
		(layer "F.Cu")
		(at 400.567144 -57.332626)
		(property "Reference" "R6828"
			(at 0 0 0)
			(layer "F.SilkS")
			(hide yes)
			(effects
				(font
					(size 1.27 1.27)
				)
			)
		)
		(property "Value" ""
			(at 0 0 0)
			(layer "F.Fab")
			(effects
				(font
					(size 1.27 1.27)
				)
			)
		)
		(duplicate_pad_numbers_are_jumpers no)
		(fp_line
			(start -0.7874 -0.4064)
			(end 0.7874 -0.4064)
			(stroke
				(width 0.1524)
				(type default)
			)
			(layer "F.SilkS")
		)
		(fp_line
			(start -0.7874 0.4064)
			(end -0.7874 -0.4064)
			(stroke
				(width 0.1524)
				(type default)
			)
			(layer "F.SilkS")
		)
		(fp_line
			(start 0.7874 -0.4064)
			(end 0.7874 0.4064)
			(stroke
				(width 0.1524)
				(type default)
			)
			(layer "F.SilkS")
		)
		(fp_line
			(start 0.7874 0.4064)
			(end -0.7874 0.4064)
			(stroke
				(width 0.1524)
				(type default)
			)
			(layer "F.SilkS")
		)
		(fp_line
			(start -0.67945 -0.305054)
			(end -0.12065 -0.305054)
			(stroke
				(width 0.1)
				(type default)
			)
			(layer "F.Fab")
		)
		(fp_line
			(start -0.67945 0.3048)
			(end -0.67945 -0.305054)
			(stroke
				(width 0.1)
				(type default)
			)
			(layer "F.Fab")
		)
		(fp_line
			(start -0.12065 -0.305054)
			(end -0.12065 -0.2794)
			(stroke
				(width 0.1)
				(type default)
			)
			(layer "F.Fab")
		)
		(fp_line
			(start -0.12065 -0.2794)
			(end 0.12065 -0.2794)
			(stroke
				(width 0.1)
				(type default)
			)
			(layer "F.Fab")
		)
		(fp_line
			(start -0.12065 0.2794)
			(end -0.12065 0.3048)
			(stroke
				(width 0.1)
				(type default)
			)
			(layer "F.Fab")
		)
		(fp_line
			(start -0.12065 0.3048)
			(end -0.67945 0.3048)
			(stroke
				(width 0.1)
				(type default)
			)
			(layer "F.Fab")
		)
		(fp_line
			(start 0.120396 0.2794)
			(end -0.12065 0.2794)
			(stroke
				(width 0.1)
				(type default)
			)
			(layer "F.Fab")
		)
		(fp_line
			(start 0.120396 0.3048)
			(end 0.120396 0.2794)
			(stroke
				(width 0.1)
				(type default)
			)
			(layer "F.Fab")
		)
		(fp_line
			(start 0.12065 -0.3048)
			(end 0.67945 -0.3048)
			(stroke
				(width 0.1)
				(type default)
			)
			(layer "F.Fab")
		)
		(fp_line
			(start 0.12065 -0.2794)
			(end 0.12065 -0.3048)
			(stroke
				(width 0.1)
				(type default)
			)
			(layer "F.Fab")
		)
		(fp_line
			(start 0.67945 -0.3048)
			(end 0.67945 0.3048)
			(stroke
				(width 0.1)
				(type default)
			)
			(layer "F.Fab")
		)
		(fp_line
			(start 0.67945 0.3048)
			(end 0.120396 0.3048)
			(stroke
				(width 0.1)
				(type default)
			)
			(layer "F.Fab")
		)
		(pad "1" smd circle
			(at -0.40005 0)
			(size 0 0)
			(layers "F.Cu" "F.Mask" "F.Paste")
			(net "SSD13_PWR_EN_R")
		)
		(pad "2" smd circle
			(at 0.40005 0)
			(size 0 0)
			(layers "F.Cu" "F.Mask" "F.Paste")
			(net "GND")
		)
	)
	(footprint ""
		(layer "F.Cu")
		(at 397.146018 -46.4439 180)
		(property "Reference" "U76"
			(at 0.550418 -2.40157 0)
			(unlocked yes)
			(layer "F.SilkS")
			(effects
				(font
					(size 0.7874 0.5842)
					(thickness 0.1524)
				)
			)
		)
		(property "Value" ""
			(at 0 0 180)
			(layer "F.Fab")
			(effects
				(font
					(size 1.27 1.27)
				)
			)
		)
		(duplicate_pad_numbers_are_jumpers no)
		(fp_line
			(start 1.500124 1.500124)
			(end 1.004062 1.500124)
			(stroke
				(width 0.1524)
				(type default)
			)
			(layer "F.SilkS")
		)
		(fp_line
			(start 1.500124 1.004062)
			(end 1.500124 1.500124)
			(stroke
				(width 0.1524)
				(type default)
			)
			(layer "F.SilkS")
		)
		(fp_line
			(start 1.500124 -1.500124)
			(end 1.500124 -1.004062)
			(stroke
				(width 0.1524)
				(type default)
			)
			(layer "F.SilkS")
		)
		(fp_line
			(start 1.004062 -1.500124)
			(end 1.500124 -1.500124)
			(stroke
				(width 0.1524)
				(type default)
			)
			(layer "F.SilkS")
		)
		(fp_line
			(start -1.004062 1.500124)
			(end -1.500124 1.500124)
			(stroke
				(width 0.1524)
				(type default)
			)
			(layer "F.SilkS")
		)
		(fp_line
			(start -1.500124 1.500124)
			(end -1.500124 1.004062)
			(stroke
				(width 0.1524)
				(type default)
			)
			(layer "F.SilkS")
		)
		(fp_line
			(start -1.500124 -1.004062)
			(end -1.500124 -1.500124)
			(stroke
				(width 0.1524)
				(type default)
			)
			(layer "F.SilkS")
		)
		(fp_line
			(start -1.500124 -1.500124)
			(end -1.004062 -1.500124)
			(stroke
				(width 0.1524)
				(type default)
			)
			(layer "F.SilkS")
		)
		(fp_poly
			(pts
				(xy -1.945894 -2.155952) (xy -2.664206 -1.43764) (xy -1.586738 -1.078484)
			)
			(stroke
				(width 0)
				(type default)
			)
			(fill yes)
			(layer "F.SilkS")
		)
		(fp_line
			(start 1.500124 1.500124)
			(end -1.500124 1.500124)
			(stroke
				(width 0.1)
				(type default)
			)
			(layer "F.Fab")
		)
		(fp_line
			(start 1.500124 -1.500124)
			(end 1.500124 1.500124)
			(stroke
				(width 0.1)
				(type default)
			)
			(layer "F.Fab")
		)
		(fp_line
			(start -1.500124 1.500124)
			(end -1.500124 -1.500124)
			(stroke
				(width 0.1)
				(type default)
			)
			(layer "F.Fab")
		)
		(fp_line
			(start -1.500124 -1.500124)
			(end 1.500124 -1.500124)
			(stroke
				(width 0.1)
				(type default)
			)
			(layer "F.Fab")
		)
		(fp_poly
			(pts
				(xy -2.847848 -1.258062) (xy -2.847848 -0.242062) (xy -1.831848 -0.750062)
			)
			(stroke
				(width 0)
				(type default)
			)
			(fill yes)
			(layer "F.Fab")
		)
		(pad "1" smd rect
			(at -1.400048 -0.750062 90)
			(size 0.2286 0.6096)
			(layers "F.Cu" "F.Mask" "F.Paste")
			(net "SSD13_ADC_A1")
		)
		(pad "2" smd rect
			(at -1.400048 -0.249936 90)
			(size 0.2286 0.6096)
			(layers "F.Cu" "F.Mask" "F.Paste")
			(net "SSD13_ADC_A0")
		)
		(pad "3" smd rect
			(at -1.400048 0.249936 90)
			(size 0.2286 0.6096)
			(layers "F.Cu" "F.Mask" "F.Paste")
			(net "SSD13_ADC_ALERT_N")
		)
		(pad "4" smd rect
			(at -1.400048 0.750062 90)
			(size 0.2286 0.6096)
			(layers "F.Cu" "F.Mask" "F.Paste")
			(net "SMB_SSD13_ADC_SDA")
		)
		(pad "5" smd rect
			(at -0.750062 1.400048 180)
			(size 0.2286 0.6096)
			(layers "F.Cu" "F.Mask" "F.Paste")
			(net "SMB_SSD13_ADC_SCL")
		)
		(pad "6" smd rect
			(at -0.249936 1.400048 180)
			(size 0.2286 0.6096)
			(layers "F.Cu" "F.Mask" "F.Paste")
			(net "Net_8684")
		)
		(pad "7" smd rect
			(at 0.249936 1.400048 180)
			(size 0.2286 0.6096)
			(layers "F.Cu" "F.Mask" "F.Paste")
			(net "Net_8683")
		)
		(pad "8" smd rect
			(at 0.750062 1.400048 180)
			(size 0.2286 0.6096)
			(layers "F.Cu" "F.Mask" "F.Paste")
			(net "Net_8682")
		)
		(pad "9" smd rect
			(at 1.400048 0.750062 90)
			(size 0.2286 0.6096)
			(layers "F.Cu" "F.Mask" "F.Paste")
			(net "P3V3_AUX")
		)
		(pad "10" smd rect
			(at 1.400048 0.249936 90)
			(size 0.2286 0.6096)
			(layers "F.Cu" "F.Mask" "F.Paste")
			(net "GND")
		)
		(pad "11" smd rect
			(at 1.400048 -0.249936 90)
			(size 0.2286 0.6096)
			(layers "F.Cu" "F.Mask" "F.Paste")
			(net "P12V_SSD13_R")
		)
		(pad "12" smd rect
			(at 1.400048 -0.750062 90)
			(size 0.2286 0.6096)
			(layers "F.Cu" "F.Mask" "F.Paste")
			(net "P12V_SSD13_VIN_N")
		)
		(pad "13" smd rect
			(at 0.750062 -1.400048 180)
			(size 0.2286 0.6096)
			(layers "F.Cu" "F.Mask" "F.Paste")
			(net "P12V_SSD13_VIN_P")
		)
		(pad "14" smd rect
			(at 0.249936 -1.400048 180)
			(size 0.2286 0.6096)
			(layers "F.Cu" "F.Mask" "F.Paste")
			(net "Net_8681")
		)
		(pad "15" smd rect
			(at -0.249936 -1.400048 180)
			(size 0.2286 0.6096)
			(layers "F.Cu" "F.Mask" "F.Paste")
			(net "Net_8680")
		)
		(pad "16" smd rect
			(at -0.750062 -1.400048 180)
			(size 0.2286 0.6096)
			(layers "F.Cu" "F.Mask" "F.Paste")
			(net "Net_8679")
		)
		(pad "TH" smd rect
			(at 0 0 180)
			(size 1.7018 1.7018)
			(layers "F.Cu" "F.Mask" "F.Paste")
			(net "GND")
		)
		(zone
			(layer "F.Cu")
			(hatch none 0.5)
			(connect_pads
				(clearance 0)
			)
			(min_thickness 0.25)
			(keepout
				(tracks not_allowed)
				(vias allowed)
				(pads allowed)
				(copperpour not_allowed)
				(footprints allowed)
			)
			(placement
				(enabled no)
				(sheetname "")
			)
			(fill
				(thermal_gap 0.5)
				(thermal_bridge_width 0.5)
				(island_removal_mode 0)
			)
			(polygon
				(pts
					(xy 398.190466 -46.4185) (xy 398.190466 -45.399452) (xy 396.10157 -45.399452) (xy 396.10157 -47.488348)
					(xy 398.190466 -47.488348) (xy 398.190466 -46.4439) (xy 398.047718 -46.4439) (xy 398.047718 -47.3456)
					(xy 396.244318 -47.3456) (xy 396.244318 -45.5422) (xy 398.047718 -45.5422) (xy 398.047718 -46.4185)
				)
			)
		)
	)
)
